# SCM (Grand Teton) — schematic netlist excerpt (pin names and nets, part order shuffled) for the footprints in the layout excerpt that follows; sources: Cadence DE-HDL packaged netlist, KiCad conversion of 12092022_DA0F0TMDCD0_F0T_Management_Board_D_brd_V3_OCP.brd

R579  Q_RES  0 5% CHIP  pkg 0402LF  page 36 : A = FM_DEBUG_PORT_PRSNT_N ; B = FM_DEBUG_PORT_R2_PRSNT_N
R599  Q_RES  750 1% CHIP  pkg 0402LF  page 47 : A = LED_POSTCODE_5 ; B = LED_POSTCODE_5_R

(kicad_pcb
	(version 20260206)
	(generator "pcbnew")
	(generator_version "10.0")
	(general
		(thickness 1.6)
		(legacy_teardrops no)
	)
	(paper "A4")
	(title_block
		(title "12092022_DA0F0TMDCD0_F0T_Management_Board_D_brd_V3_OCP.brd")
		(comment 1 "Grand Teton / footprints 253-254 of 1440")
	)
	(layers
		(0 "F.Cu" signal "TOP")
		(4 "In1.Cu" signal "GND")
		(6 "In2.Cu" signal "IN1")
		(8 "In3.Cu" signal "GND1")
		(10 "In4.Cu" signal "IN2")
		(12 "In5.Cu" signal "VCC")
		(14 "In6.Cu" signal "VCC1")
		(16 "In7.Cu" signal "IN3")
		(18 "In8.Cu" signal "GND2")
		(20 "In9.Cu" signal "IN4")
		(22 "In10.Cu" signal "GND3")
		(2 "B.Cu" signal "BOTTOM")
		(9 "F.Adhes" user "F.Adhesive")
		(11 "B.Adhes" user "B.Adhesive")
		(13 "F.Paste" user "Package Geometry/Pastemask Top")
		(15 "B.Paste" user "Package Geometry/Pastemask Bottom")
		(5 "F.SilkS" user "Ref Des/Silkscreen Top")
		(7 "B.SilkS" user "Ref Des/Silkscreen Bottom")
		(1 "F.Mask" user "Board Geometry/Soldermask Top")
		(3 "B.Mask" user "Board Geometry/Soldermask Bottom")
		(17 "Dwgs.User" user "User.Drawings")
		(19 "Cmts.User" user "User.Comments")
		(21 "Eco1.User" user "User.Eco1")
		(23 "Eco2.User" user "User.Eco2")
		(25 "Edge.Cuts" user "Board Geometry/Outline")
		(27 "Margin" user)
		(31 "F.CrtYd" user "Package Geometry/Place Bound Top")
		(29 "B.CrtYd" user "Package Geometry/Place Bound Bottom")
		(35 "F.Fab" user "Ref Des/Assembly Top")
		(33 "B.Fab" user "Ref Des/Assembly Bottom")
	)
	(footprint ""
		(layer "F.Cu")
		(at 23.495 -102.743 -90)
		(property "Reference" "R579"
			(at 0 0 270)
			(layer "F.SilkS")
			(hide yes)
			(effects
				(font
					(size 1.27 1.27)
				)
			)
		)
		(property "Value" ""
			(at 0 0 270)
			(layer "F.Fab")
			(effects
				(font
					(size 1.27 1.27)
				)
			)
		)
		(duplicate_pad_numbers_are_jumpers no)
		(fp_line
			(start -0.7874 0.4064)
			(end -0.7874 -0.4064)
			(stroke
				(width 0.1524)
				(type default)
			)
			(layer "F.SilkS")
		)
		(fp_line
			(start 0.7874 0.4064)
			(end -0.7874 0.4064)
			(stroke
				(width 0.1524)
				(type default)
			)
			(layer "F.SilkS")
		)
		(fp_line
			(start -0.7874 -0.4064)
			(end 0.7874 -0.4064)
			(stroke
				(width 0.1524)
				(type default)
			)
			(layer "F.SilkS")
		)
		(fp_line
			(start 0.7874 -0.4064)
			(end 0.7874 0.4064)
			(stroke
				(width 0.1524)
				(type default)
			)
			(layer "F.SilkS")
		)
		(fp_line
			(start -0.67945 0.3048)
			(end -0.67945 -0.305054)
			(stroke
				(width 0.1)
				(type default)
			)
			(layer "F.Fab")
		)
		(fp_line
			(start -0.12065 0.3048)
			(end -0.67945 0.3048)
			(stroke
				(width 0.1)
				(type default)
			)
			(layer "F.Fab")
		)
		(fp_line
			(start 0.120396 0.3048)
			(end 0.120396 0.2794)
			(stroke
				(width 0.1)
				(type default)
			)
			(layer "F.Fab")
		)
		(fp_line
			(start 0.67945 0.3048)
			(end 0.120396 0.3048)
			(stroke
				(width 0.1)
				(type default)
			)
			(layer "F.Fab")
		)
		(fp_line
			(start -0.12065 0.2794)
			(end -0.12065 0.3048)
			(stroke
				(width 0.1)
				(type default)
			)
			(layer "F.Fab")
		)
		(fp_line
			(start 0.120396 0.2794)
			(end -0.12065 0.2794)
			(stroke
				(width 0.1)
				(type default)
			)
			(layer "F.Fab")
		)
		(fp_line
			(start -0.12065 -0.2794)
			(end 0.12065 -0.2794)
			(stroke
				(width 0.1)
				(type default)
			)
			(layer "F.Fab")
		)
		(fp_line
			(start 0.12065 -0.2794)
			(end 0.12065 -0.3048)
			(stroke
				(width 0.1)
				(type default)
			)
			(layer "F.Fab")
		)
		(fp_line
			(start 0.12065 -0.3048)
			(end 0.67945 -0.3048)
			(stroke
				(width 0.1)
				(type default)
			)
			(layer "F.Fab")
		)
		(fp_line
			(start 0.67945 -0.3048)
			(end 0.67945 0.3048)
			(stroke
				(width 0.1)
				(type default)
			)
			(layer "F.Fab")
		)
		(fp_line
			(start -0.67945 -0.305054)
			(end -0.12065 -0.305054)
			(stroke
				(width 0.1)
				(type default)
			)
			(layer "F.Fab")
		)
		(fp_line
			(start -0.12065 -0.305054)
			(end -0.12065 -0.2794)
			(stroke
				(width 0.1)
				(type default)
			)
			(layer "F.Fab")
		)
		(pad "1" smd circle
			(at -0.40005 0 270)
			(size 0 0)
			(layers "F.Cu" "F.Mask" "F.Paste")
			(net "FM_DEBUG_PORT_PRSNT_N")
		)
		(pad "2" smd circle
			(at 0.40005 0 270)
			(size 0 0)
			(layers "F.Cu" "F.Mask" "F.Paste")
			(net "FM_DEBUG_PORT_R2_PRSNT_N")
		)
	)
	(footprint ""
		(layer "F.Cu")
		(at 80.4418 -30.8356 -90)
		(property "Reference" "R599"
			(at 0 0 270)
			(layer "F.SilkS")
			(hide yes)
			(effects
				(font
					(size 1.27 1.27)
				)
			)
		)
		(property "Value" ""
			(at 0 0 270)
			(layer "F.Fab")
			(effects
				(font
					(size 1.27 1.27)
				)
			)
		)
		(duplicate_pad_numbers_are_jumpers no)
		(fp_line
			(start -0.7874 0.4064)
			(end -0.7874 -0.4064)
			(stroke
				(width 0.1524)
				(type default)
			)
			(layer "F.SilkS")
		)
		(fp_line
			(start 0.7874 0.4064)
			(end -0.7874 0.4064)
			(stroke
				(width 0.1524)
				(type default)
			)
			(layer "F.SilkS")
		)
		(fp_line
			(start -0.7874 -0.4064)
			(end 0.7874 -0.4064)
			(stroke
				(width 0.1524)
				(type default)
			)
			(layer "F.SilkS")
		)
		(fp_line
			(start 0.7874 -0.4064)
			(end 0.7874 0.4064)
			(stroke
				(width 0.1524)
				(type default)
			)
			(layer "F.SilkS")
		)
		(fp_line
			(start -0.67945 0.3048)
			(end -0.67945 -0.305054)
			(stroke
				(width 0.1)
				(type default)
			)
			(layer "F.Fab")
		)
		(fp_line
			(start -0.12065 0.3048)
			(end -0.67945 0.3048)
			(stroke
				(width 0.1)
				(type default)
			)
			(layer "F.Fab")
		)
		(fp_line
			(start 0.120396 0.3048)
			(end 0.120396 0.2794)
			(stroke
				(width 0.1)
				(type default)
			)
			(layer "F.Fab")
		)
		(fp_line
			(start 0.67945 0.3048)
			(end 0.120396 0.3048)
			(stroke
				(width 0.1)
				(type default)
			)
			(layer "F.Fab")
		)
		(fp_line
			(start -0.12065 0.2794)
			(end -0.12065 0.3048)
			(stroke
				(width 0.1)
				(type default)
			)
			(layer "F.Fab")
		)
		(fp_line
			(start 0.120396 0.2794)
			(end -0.12065 0.2794)
			(stroke
				(width 0.1)
				(type default)
			)
			(layer "F.Fab")
		)
		(fp_line
			(start -0.12065 -0.2794)
			(end 0.12065 -0.2794)
			(stroke
				(width 0.1)
				(type default)
			)
			(layer "F.Fab")
		)
		(fp_line
			(start 0.12065 -0.2794)
			(end 0.12065 -0.3048)
			(stroke
				(width 0.1)
				(type default)
			)
			(layer "F.Fab")
		)
		(fp_line
			(start 0.12065 -0.3048)
			(end 0.67945 -0.3048)
			(stroke
				(width 0.1)
				(type default)
			)
			(layer "F.Fab")
		)
		(fp_line
			(start 0.67945 -0.3048)
			(end 0.67945 0.3048)
			(stroke
				(width 0.1)
				(type default)
			)
			(layer "F.Fab")
		)
		(fp_line
			(start -0.67945 -0.305054)
			(end -0.12065 -0.305054)
			(stroke
				(width 0.1)
				(type default)
			)
			(layer "F.Fab")
		)
		(fp_line
			(start -0.12065 -0.305054)
			(end -0.12065 -0.2794)
			(stroke
				(width 0.1)
				(type default)
			)
			(layer "F.Fab")
		)
		(pad "1" smd circle
			(at -0.40005 0 270)
			(size 0 0)
			(layers "F.Cu" "F.Mask" "F.Paste")
			(net "LED_POSTCODE_5")
		)
		(pad "2" smd circle
			(at 0.40005 0 270)
			(size 0 0)
			(layers "F.Cu" "F.Mask" "F.Paste")
			(net "LED_POSTCODE_5_R")
		)
	)
)
